#ISCELL
  mstr_misc dns *
  *
#ISCELL
  mstr_symbols intel_corp_bpage *
  *
#ISCELL
  mstr_symbols pvddq_ghj *
  page224_i1
#CELL
  mstr_discrete ir354xx *
  page224_i110
#CELL
  mstr_discrete ir354xx *
  page224_i111
#CELL
  mstr_discrete res *
  page224_i112
#ISCELL
  mstr_symbols gnd *
  page224_i113
#CELL
  mstr_discrete res *
  page224_i114
#ISCELL
  mstr_symbols gnd *
  page224_i115
#CELL
  dev_discrete cap_a *
  page224_i117
#ISCELL
  mstr_symbols gnd *
  page224_i118
#CELL
  w_hdl 3d01r5f-gp *
  page224_i119
#ISCELL
  mstr_symbols gnd *
  page224_i120
#CELL
  w_hdl sc2k2p50v3kx-gp *
  page224_i121
#CELL
  mstr_discrete cap *
  page224_i122
#ISCELL
  mstr_symbols gnd *
  page224_i123
#CELL
  dev_discrete cap_a *
  page224_i124
#ISCELL
  mstr_symbols gnd *
  page224_i125
#CELL
  w_hdl sc2k2p50v3kx-gp *
  page224_i127
#ISCELL
  mstr_symbols gnd *
  page224_i128
#CELL
  w_hdl 3d01r5f-gp *
  page224_i129
#CELL
  mstr_discrete cap *
  page224_i130
#ISCELL
  mstr_symbols gnd *
  page224_i131
#CELL
  mstr_discrete res *
  page224_i132
#CELL
  mstr_discrete res *
  page224_i133
#ISCELL
  mstr_symbols gnd *
  page224_i19
#ISCELL
  mstr_standard offpage *
  page224_i3
#ISCELL
  mstr_standard offpage *
  page224_i33
#ISCELL
  mstr_symbols gnd *
  page224_i35
#ISCELL
  mstr_standard offpage *
  page224_i4
#CELL
  mstr_discrete cap *
  page224_i44
#CELL
  mstr_discrete cap *
  page224_i45
#CELL
  mstr_discrete cap *
  page224_i46
#CELL
  mstr_discrete cap *
  page224_i47
#CELL
  mstr_discrete cap *
  page224_i48
#CELL
  mstr_discrete cap *
  page224_i50
#CELL
  dev_discrete cap_a *
  page224_i51
#CELL
  mstr_discrete res *
  page224_i52
#CELL
  dev_discrete cap_a *
  page224_i53
#CELL
  mstr_discrete cap *
  page224_i54
#CELL
  mstr_discrete inductor *
  page224_i55
#ISCELL
  mstr_standard offpage *
  page224_i58
#CELL
  mstr_discrete cap *
  page224_i6
#ISCELL
  mstr_standard offpage *
  page224_i61
#ISCELL
  mstr_standard offpage *
  page224_i62
#ISCELL
  mstr_standard offpage *
  page224_i63
#ISCELL
  mstr_symbols pvddq_ghj *
  page224_i64
#CELL
  mstr_discrete inductor *
  page224_i65
#CELL
  mstr_discrete cap *
  page224_i68
#ISCELL
  mstr_symbols gnd *
  page224_i69
#ISCELL
  mstr_symbols gnd *
  page224_i7
#ISCELL
  mstr_symbols gnd *
  page224_i70
#CELL
  mstr_discrete cap *
  page224_i72
#CELL
  dev_discrete cap_a *
  page224_i73
#CELL
  mstr_discrete cap *
  page224_i75
#CELL
  mstr_discrete res *
  page224_i76
#CELL
  mstr_discrete cap *
  page224_i77
#CELL
  dev_discrete cap_a *
  page224_i78
#CELL
  mstr_discrete cap *
  page224_i79
#CELL
  mstr_discrete cap *
  page224_i80
#CELL
  mstr_discrete cap *
  page224_i81
#ISCELL
  mstr_standard offpage *
  page224_i82
#ISCELL
  mstr_symbols vcc_core *
  page224_i83
#CELL
  mstr_discrete cap *
  page224_i84
#ISCELL
  mstr_symbols gnd *
  page224_i85
#ISCELL
  mstr_symbols p5v_stby *
  page224_i87
#ISCELL
  mstr_symbols p5v_stby *
  page224_i88
#ISCELL
  mstr_symbols vcc_core *
  page224_i89
